(kicad_pcb
	(version 20241229)
	(generator "pcbnew")
	(generator_version "9.0")
	(general
		(thickness 1.61)
		(legacy_teardrops no)
	)
	(paper "A3")
	(title_block
		(title "RDIMM DDR5 Tester")
		(date "2026-05-21")
		(rev "2.2.0")
		(company "Antmicro")
		(comment 9 "footprints 311-312 of 796")
	)
	(layers
		(0 "F.Cu" signal)
		(4 "In1.Cu" power)
		(6 "In2.Cu" mixed)
		(8 "In3.Cu" power)
		(10 "In4.Cu" mixed)
		(12 "In5.Cu" power)
		(14 "In6.Cu" mixed)
		(16 "In7.Cu" power)
		(18 "In8.Cu" power)
		(20 "In9.Cu" mixed)
		(22 "In10.Cu" power)
		(2 "B.Cu" signal)
		(9 "F.Adhes" user "F.Adhesive")
		(11 "B.Adhes" user "B.Adhesive")
		(13 "F.Paste" user)
		(15 "B.Paste" user)
		(5 "F.SilkS" user "F.Silkscreen")
		(7 "B.SilkS" user "B.Silkscreen")
		(1 "F.Mask" user)
		(3 "B.Mask" user)
		(17 "Dwgs.User" user "User.Drawings")
		(19 "Cmts.User" user "User.Comments")
		(21 "Eco1.User" user "User.Eco1")
		(23 "Eco2.User" user "User.Eco2")
		(25 "Edge.Cuts" user)
		(27 "Margin" user)
		(31 "F.CrtYd" user "F.Courtyard")
		(29 "B.CrtYd" user "B.Courtyard")
		(35 "F.Fab" user)
		(33 "B.Fab" user)
	)
	(footprint "antmicro-footprints:QFN-36-1EP_6x6mm_P0.5mm_EP3.7x3.7mm"
		(layer "F.Cu")
		(at 159.81 161.799999 -90)
		(property "Reference" "U39"
			(at 4.61 -1.52 0)
			(unlocked yes)
			(layer "F.SilkS")
			(effects
				(font
					(size 0.7 0.7)
					(thickness 0.15)
				)
				(justify left bottom)
			)
		)
		(property "Value" "SI5319C-C-GM-ND"
			(at -3.62 4.605 270)
			(unlocked yes)
			(layer "F.Fab")
			(effects
				(font
					(size 0.7 0.7)
					(thickness 0.15)
				)
				(justify left bottom)
			)
		)
		(property "Datasheet" "https://www.skyworksinc.com/-/media/Skyworks/SL/documents/public/data-sheets/Si5319.pdf"
			(at 0 0 270)
			(layer "F.Fab")
			(hide yes)
			(effects
				(font
					(size 1.27 1.27)
					(thickness 0.15)
				)
			)
		)
		(property "MPN" "SI5319C-C-GM-ND"
			(at 0 0 270)
			(unlocked yes)
			(layer "F.Fab")
			(hide yes)
			(effects
				(font
					(size 1 1)
					(thickness 0.15)
				)
			)
		)
		(property "Manufacturer" "Skyworks Solutions"
			(at 0 0 270)
			(unlocked yes)
			(layer "F.Fab")
			(hide yes)
			(effects
				(font
					(size 1 1)
					(thickness 0.15)
				)
			)
		)
		(property "Author" "Antmicro"
			(at 0 0 270)
			(unlocked yes)
			(layer "F.Fab")
			(hide yes)
			(effects
				(font
					(size 1 1)
					(thickness 0.15)
				)
			)
		)
		(property "License" "Apache-2.0"
			(at 0 0 270)
			(unlocked yes)
			(layer "F.Fab")
			(hide yes)
			(effects
				(font
					(size 1 1)
					(thickness 0.15)
				)
			)
		)
		(sheetname "/FPGA MGT Interface/")
		(sheetfile "fpga-mgt.kicad_sch")
		(attr smd)
		(fp_line
			(start -3.049 3.049)
			(end -2.4 3.049)
			(stroke
				(width 0.15)
				(type solid)
			)
			(layer "F.SilkS")
		)
		(fp_line
			(start 2.4 3.049)
			(end 3.049 3.049)
			(stroke
				(width 0.15)
				(type solid)
			)
			(layer "F.SilkS")
		)
		(fp_line
			(start 3.049 3.049)
			(end 3.049 2.4)
			(stroke
				(width 0.15)
				(type solid)
			)
			(layer "F.SilkS")
		)
		(fp_line
			(start -3.049 2.4)
			(end -3.049 3.049)
			(stroke
				(width 0.15)
				(type solid)
			)
			(layer "F.SilkS")
		)
		(fp_line
			(start -3.049 -2.4)
			(end -3.049 -3.049)
			(stroke
				(width 0.15)
				(type solid)
			)
			(layer "F.SilkS")
		)
		(fp_line
			(start -3.049 -3.049)
			(end -2.4 -3.049)
			(stroke
				(width 0.15)
				(type solid)
			)
			(layer "F.SilkS")
		)
		(fp_line
			(start 2.4 -3.049)
			(end 3.049 -3.049)
			(stroke
				(width 0.15)
				(type solid)
			)
			(layer "F.SilkS")
		)
		(fp_line
			(start 3.049 -3.049)
			(end 3.049 -2.4)
			(stroke
				(width 0.15)
				(type solid)
			)
			(layer "F.SilkS")
		)
		(fp_circle
			(center -3.4 -2.5)
			(end -3.35 -2.5)
			(stroke
				(width 0.15)
				(type solid)
			)
			(fill yes)
			(layer "F.SilkS")
		)
		(fp_circle
			(center -3.4 -2.5)
			(end -3.299 -2.5)
			(stroke
				(width 0.15)
				(type solid)
			)
			(fill no)
			(layer "F.SilkS")
		)
		(fp_poly
			(pts
				(xy -1.49 0.18) (xy -0.18 0.18) (xy -0.18 1.49) (xy -1.49 1.49)
			)
			(stroke
				(width 0.01)
				(type solid)
			)
			(fill yes)
			(layer "F.Paste")
		)
		(fp_poly
			(pts
				(xy 0.18 0.18) (xy 1.49 0.18) (xy 1.49 1.49) (xy 0.18 1.49)
			)
			(stroke
				(width 0.01)
				(type solid)
			)
			(fill yes)
			(layer "F.Paste")
		)
		(fp_poly
			(pts
				(xy -1.49 -1.49) (xy -0.18 -1.49) (xy -0.18 -0.18) (xy -1.49 -0.18)
			)
			(stroke
				(width 0.01)
				(type solid)
			)
			(fill yes)
			(layer "F.Paste")
		)
		(fp_poly
			(pts
				(xy 0.18 -1.49) (xy 1.49 -1.49) (xy 1.49 -0.18) (xy 0.18 -0.18)
			)
			(stroke
				(width 0.01)
				(type solid)
			)
			(fill yes)
			(layer "F.Paste")
		)
		(fp_line
			(start -3.62 3.62)
			(end -3.62 -3.62)
			(stroke
				(width 0.05)
				(type solid)
			)
			(layer "F.CrtYd")
		)
		(fp_line
			(start 3.62 3.62)
			(end -3.62 3.62)
			(stroke
				(width 0.05)
				(type solid)
			)
			(layer "F.CrtYd")
		)
		(fp_line
			(start -3.62 -3.62)
			(end 3.62 -3.62)
			(stroke
				(width 0.05)
				(type solid)
			)
			(layer "F.CrtYd")
		)
		(fp_line
			(start 3.62 -3.62)
			(end 3.62 3.62)
			(stroke
				(width 0.05)
				(type solid)
			)
			(layer "F.CrtYd")
		)
		(fp_line
			(start -3.049 3.049)
			(end -3.049 -3.049)
			(stroke
				(width 0.15)
				(type solid)
			)
			(layer "F.Fab")
		)
		(fp_line
			(start 3.049 3.049)
			(end -3.049 3.049)
			(stroke
				(width 0.15)
				(type solid)
			)
			(layer "F.Fab")
		)
		(fp_line
			(start 3.049 3.049)
			(end 3.049 -3.049)
			(stroke
				(width 0.15)
				(type solid)
			)
			(layer "F.Fab")
		)
		(fp_line
			(start 3.049 -3.049)
			(end -3.049 -3.049)
			(stroke
				(width 0.15)
				(type solid)
			)
			(layer "F.Fab")
		)
		(fp_circle
			(center -3.4 -2.5)
			(end -3.299 -2.5)
			(stroke
				(width 0.15)
				(type solid)
			)
			(fill no)
			(layer "F.Fab")
		)
		(fp_text user "${REFERENCE}"
			(at -3.97 9.005 270)
			(unlocked yes)
			(layer "F.Fab")
			(effects
				(font
					(size 0.7 0.7)
					(thickness 0.15)
				)
				(justify left bottom)
			)
		)
		(fp_text user "License: Apache-2.0"
			(at -3.97 6.605 270)
			(layer "F.Fab")
			(effects
				(font
					(size 0.7 0.7)
					(thickness 0.15)
				)
				(justify left bottom)
			)
		)
		(fp_text user "Author: Antmicro"
			(at -3.97 7.805 270)
			(layer "F.Fab")
			(effects
				(font
					(size 0.7 0.7)
					(thickness 0.15)
				)
				(justify left bottom)
			)
		)
		(pad "1" smd rect
			(at -2.815 -2 270)
			(size 1.1 0.26)
			(layers "F.Cu" "F.Mask" "F.Paste")
			(net 531 "~{SI_5319_RST}")
			(pinfunction "~{RST}")
			(pintype "input")
		)
		(pad "2" smd rect
			(at -2.815 -1.5 270)
			(size 1.1 0.26)
			(layers "F.Cu" "F.Mask" "F.Paste")
			(net 761 "unconnected-(U39-NC-Pad2)")
			(pinfunction "NC")
			(pintype "no_connect")
		)
		(pad "3" smd rect
			(at -2.815 -1 270)
			(size 1.1 0.26)
			(layers "F.Cu" "F.Mask" "F.Paste")
			(net 762 "INT_CB")
			(pinfunction "INT_CB")
			(pintype "output")
		)
		(pad "4" smd rect
			(at -2.815 -0.5 270)
			(size 1.1 0.26)
			(layers "F.Cu" "F.Mask" "F.Paste")
			(net 763 "unconnected-(U39-NC-Pad4)")
			(pinfunction "NC")
			(pintype "no_connect")
		)
		(pad "5" smd rect
			(at -2.815 0 270)
			(size 1.1 0.26)
			(layers "F.Cu" "F.Mask" "F.Paste")
			(net 151 "+3V3")
			(pinfunction "VDD")
			(pintype "power_in")
		)
		(pad "6" smd rect
			(at -2.815 0.5 270)
			(size 1.1 0.26)
			(layers "F.Cu" "F.Mask" "F.Paste")
			(net 764 "/FPGA MGT Interface/XA")
			(pinfunction "XA")
			(pintype "input")
		)
		(pad "7" smd rect
			(at -2.815 1 270)
			(size 1.1 0.26)
			(layers "F.Cu" "F.Mask" "F.Paste")
			(net 765 "/FPGA MGT Interface/XB")
			(pinfunction "XB")
			(pintype "input")
		)
		(pad "8" smd rect
			(at -2.815 1.5 270)
			(size 1.1 0.26)
			(layers "F.Cu" "F.Mask" "F.Paste")
			(net 1 "GND")
			(pinfunction "GND")
			(pintype "power_in")
		)
		(pad "9" smd rect
			(at -2.815 2 270)
			(size 1.1 0.26)
			(layers "F.Cu" "F.Mask" "F.Paste")
			(net 766 "unconnected-(U39-NC-Pad9)")
			(pinfunction "NC")
			(pintype "no_connect")
		)
		(pad "10" smd rect
			(at -2 2.815 270)
			(size 0.26 1.1)
			(layers "F.Cu" "F.Mask" "F.Paste")
			(net 151 "+3V3")
			(pinfunction "VDD")
			(pintype "passive")
		)
		(pad "11" smd rect
			(at -1.5 2.815 270)
			(size 0.26 1.1)
			(layers "F.Cu" "F.Mask" "F.Paste")
			(net 534 "Net-(U39-RATE0)")
			(pinfunction "RATE0")
			(pintype "input")
		)
		(pad "12" smd rect
			(at -1 2.815 270)
			(size 0.26 1.1)
			(layers "F.Cu" "F.Mask" "F.Paste")
			(net 669 "unconnected-(U39-NC-Pad12)")
			(pinfunction "NC")
			(pintype "no_connect")
		)
		(pad "13" smd rect
			(at -0.5 2.815 270)
			(size 0.26 1.1)
			(layers "F.Cu" "F.Mask" "F.Paste")
			(net 670 "unconnected-(U39-NC-Pad13)")
			(pinfunction "NC")
			(pintype "no_connect")
		)
		(pad "14" smd rect
			(at 0 2.815 270)
			(size 0.26 1.1)
			(layers "F.Cu" "F.Mask" "F.Paste")
			(net 706 "unconnected-(U39-NC-Pad14)")
			(pinfunction "NC")
			(pintype "no_connect")
		)
		(pad "15" smd rect
			(at 0.5 2.815 270)
			(size 0.26 1.1)
			(layers "F.Cu" "F.Mask" "F.Paste")
			(net 542 "Net-(U39-RATE1)")
			(pinfunction "RATE1")
			(pintype "input")
		)
		(pad "16" smd rect
			(at 1 2.815 270)
			(size 0.26 1.1)
			(layers "F.Cu" "F.Mask" "F.Paste")
			(net 488 "/FPGA MGT Interface/HDMI_REC_CLK_C_P")
			(pinfunction "CKIN+")
			(pintype "input")
		)
		(pad "17" smd rect
			(at 1.5 2.815 270)
			(size 0.26 1.1)
			(layers "F.Cu" "F.Mask" "F.Paste")
			(net 489 "/FPGA MGT Interface/HDMI_REC_CLK_C_N")
			(pinfunction "CKIN-")
			(pintype "input")
		)
		(pad "18" smd rect
			(at 2 2.815 270)
			(size 0.26 1.1)
			(layers "F.Cu" "F.Mask" "F.Paste")
			(net 767 "LOL")
			(pinfunction "LOL")
			(pintype "output")
		)
		(pad "19" smd rect
			(at 2.815 2 270)
			(size 1.1 0.26)
			(layers "F.Cu" "F.Mask" "F.Paste")
			(net 1 "GND")
			(pinfunction "GND")
			(pintype "passive")
		)
		(pad "20" smd rect
			(at 2.815 1.5 270)
			(size 1.1 0.26)
			(layers "F.Cu" "F.Mask" "F.Paste")
			(net 1 "GND")
			(pinfunction "GND")
			(pintype "passive")
		)
		(pad "21" smd rect
			(at 2.815 1 270)
			(size 1.1 0.26)
			(layers "F.Cu" "F.Mask" "F.Paste")
			(net 708 "Net-(U39-CS)")
			(pinfunction "CS")
			(pintype "input")
		)
		(pad "22" smd rect
			(at 2.815 0.5 270)
			(size 1.1 0.26)
			(layers "F.Cu" "F.Mask" "F.Paste")
			(net 768 "/FPGA MGT Interface/HDMI_CTL.SCL")
			(pinfunction "SCL")
			(pintype "input")
		)
		(pad "23" smd rect
			(at 2.815 0 270)
			(size 1.1 0.26)
			(layers "F.Cu" "F.Mask" "F.Paste")
			(net 769 "/FPGA MGT Interface/HDMI_CTL.SDA")
			(pinfunction "SDA_SDO")
			(pintype "input")
		)
		(pad "24" smd rect
			(at 2.815 -0.5 270)
			(size 1.1 0.26)
			(layers "F.Cu" "F.Mask" "F.Paste")
			(net 1 "GND")
			(pinfunction "A0")
			(pintype "input")
		)
		(pad "25" smd rect
			(at 2.815 -1 270)
			(size 1.1 0.26)
			(layers "F.Cu" "F.Mask" "F.Paste")
			(net 1 "GND")
			(pinfunction "A1")
			(pintype "input")
		)
		(pad "26" smd rect
			(at 2.815 -1.5 270)
			(size 1.1 0.26)
			(layers "F.Cu" "F.Mask" "F.Paste")
			(net 1 "GND")
			(pinfunction "A2_~{SS}")
			(pintype "input")
		)
		(pad "27" smd rect
			(at 2.815 -2 270)
			(size 1.1 0.26)
			(layers "F.Cu" "F.Mask" "F.Paste")
			(net 770 "unconnected-(U39-SDI-Pad27)")
			(pinfunction "SDI")
			(pintype "input+no_connect")
		)
		(pad "28" smd rect
			(at 2 -2.815 270)
			(size 0.26 1.1)
			(layers "F.Cu" "F.Mask" "F.Paste")
			(net 389 "/FPGA MGT Interface/HDMI_SI5319_C_CLK_P")
			(pinfunction "CKOUT+")
			(pintype "output")
		)
		(pad "29" smd rect
			(at 1.5 -2.815 270)
			(size 0.26 1.1)
			(layers "F.Cu" "F.Mask" "F.Paste")
			(net 386 "/FPGA MGT Interface/HDMI_SI5319_C_CLK_N")
			(pinfunction "CKOUT-")
			(pintype "output")
		)
		(pad "30" smd rect
			(at 1 -2.815 270)
			(size 0.26 1.1)
			(layers "F.Cu" "F.Mask" "F.Paste")
			(net 750 "unconnected-(U39-NC-Pad30)")
			(pinfunction "NC")
			(pintype "no_connect")
		)
		(pad "31" smd rect
			(at 0.5 -2.815 270)
			(size 0.26 1.1)
			(layers "F.Cu" "F.Mask" "F.Paste")
			(net 1 "GND")
			(pinfunction "GND")
			(pintype "passive")
		)
		(pad "32" smd rect
			(at 0 -2.815 270)
			(size 0.26 1.1)
			(layers "F.Cu" "F.Mask" "F.Paste")
			(net 151 "+3V3")
			(pinfunction "VDD")
			(pintype "passive")
		)
		(pad "33" smd rect
			(at -0.5 -2.815 270)
			(size 0.26 1.1)
			(layers "F.Cu" "F.Mask" "F.Paste")
			(net 751 "unconnected-(U39-NC-Pad33)")
			(pinfunction "NC")
			(pintype "no_connect")
		)
		(pad "34" smd rect
			(at -1 -2.815 270)
			(size 0.26 1.1)
			(layers "F.Cu" "F.Mask" "F.Paste")
			(net 752 "unconnected-(U39-NC-Pad34)")
			(pinfunction "NC")
			(pintype "no_connect")
		)
		(pad "35" smd rect
			(at -1.5 -2.815 270)
			(size 0.26 1.1)
			(layers "F.Cu" "F.Mask" "F.Paste")
			(net 753 "unconnected-(U39-NC-Pad35)")
			(pinfunction "NC")
			(pintype "no_connect")
		)
		(pad "36" smd rect
			(at -2 -2.815 270)
			(size 0.26 1.1)
			(layers "F.Cu" "F.Mask" "F.Paste")
			(net 1 "GND")
			(pinfunction "CMODE")
			(pintype "input")
		)
		(pad "37" smd rect
			(at 0 0 270)
			(size 3.7 3.7)
			(layers "F.Cu" "F.Mask")
			(net 1 "GND")
			(pinfunction "GND")
			(pintype "passive")
		)
	)
	(footprint "antmicro-footprints:R_0402_1005Metric"
		(layer "F.Cu")
		(at 119.15 150.61 180)
		(descr "Resistor SMD 0402")
		(tags "resistor SMD 0402")
		(property "Reference" "R29"
			(at -5.11 -0.415 0)
			(layer "F.SilkS")
			(effects
				(font
					(size 0.7 0.7)
					(thickness 0.15)
				)
				(justify right bottom)
			)
		)
		(property "Value" "R_49k9_0402"
			(at -1.011843 1.772047 0)
			(layer "F.Fab")
			(effects
				(font
					(size 0.7 0.7)
					(thickness 0.15)
				)
				(justify right bottom)
			)
		)
		(property "Datasheet" "https://www.bourns.com/docs/product-datasheets/cr.pdf"
			(at 0 0 180)
			(layer "F.Fab")
			(hide yes)
			(effects
				(font
					(size 1.27 1.27)
					(thickness 0.15)
				)
			)
		)
		(property "MPN" "CR0402-FX-4992GLF"
			(at 0 0 180)
			(unlocked yes)
			(layer "F.Fab")
			(hide yes)
			(effects
				(font
					(size 1 1)
					(thickness 0.15)
				)
			)
		)
		(property "Manufacturer" "Bourns"
			(at 0 0 180)
			(unlocked yes)
			(layer "F.Fab")
			(hide yes)
			(effects
				(font
					(size 1 1)
					(thickness 0.15)
				)
			)
		)
		(property "License" "Apache-2.0"
			(at 0 0 180)
			(unlocked yes)
			(layer "F.Fab")
			(hide yes)
			(effects
				(font
					(size 1 1)
					(thickness 0.15)
				)
			)
		)
		(property "Author" "Antmicro"
			(at 0 0 180)
			(unlocked yes)
			(layer "F.Fab")
			(hide yes)
			(effects
				(font
					(size 1 1)
					(thickness 0.15)
				)
			)
		)
		(property "Val" "49k9"
			(at 0 0 180)
			(unlocked yes)
			(layer "F.Fab")
			(hide yes)
			(effects
				(font
					(size 1 1)
					(thickness 0.15)
				)
			)
		)
		(property "Tolerance" "1%"
			(at 0 0 180)
			(unlocked yes)
			(layer "F.Fab")
			(hide yes)
			(effects
				(font
					(size 1 1)
					(thickness 0.15)
				)
			)
		)
		(sheetname "/HDMI + SD Card/")
		(sheetfile "hdmi-sd-card.kicad_sch")
		(attr smd)
		(fp_rect
			(start -0.925 -0.47)
			(end 0.925 0.47)
			(stroke
				(width 0.05)
				(type default)
			)
			(fill no)
			(layer "F.CrtYd")
		)
		(fp_rect
			(start -0.5 -0.25)
			(end 0.5 0.25)
			(stroke
				(width 0.15)
				(type solid)
			)
			(fill no)
			(layer "F.Fab")
		)
		(fp_text user "License: Apache-2.0"
			(at -0.95 5.169 180)
			(layer "F.Fab")
			(effects
				(font
					(size 0.7 0.7)
					(thickness 0.15)
				)
				(justify left bottom)
			)
		)
		(fp_text user "${REFERENCE}"
			(at -0.95 3.168 180)
			(layer "F.Fab")
			(effects
				(font
					(size 0.7 0.7)
					(thickness 0.15)
				)
				(justify left bottom)
			)
		)
		(fp_text user "Author: Antmicro"
			(at -0.95 4.169 180)
			(layer "F.Fab")
			(effects
				(font
					(size 0.7 0.7)
					(thickness 0.15)
				)
				(justify left bottom)
			)
		)
		(pad "1" smd roundrect
			(at -0.48 0 180)
			(size 0.59 0.64)
			(layers "F.Cu" "F.Mask" "F.Paste")
			(roundrect_rratio 0.25)
			(net 675 "Net-(L5-Pad2)")
			(pintype "passive")
		)
		(pad "2" smd roundrect
			(at 0.48 0 180)
			(size 0.59 0.64)
			(layers "F.Cu" "F.Mask" "F.Paste")
			(roundrect_rratio 0.25)
			(net 322 "Net-(C300-Pad2)")
			(pintype "passive")
		)
	)
)
